# T6G (Grand Teton) — schematic netlist excerpt (pin names and nets, part order shuffled) for the footprints in the layout excerpt that follows; sources: Cadence DE-HDL packaged netlist, KiCad conversion of 04192023_DAF0TMB3IC0_F0TG_MB_C_brd_V02_OCP.brd

PR270  Q_RES  8.87K 1% EMPTY  pkg 0402LF  page 220 : A = PVDDCR_CPU1_P1_LSET5 ; B = GND
PC2167  Q_CAP  100PF 50V 5% NPO  pkg 0402  page 141 : A = P12V_OCP_IMON_2 ; B = GND

(kicad_pcb
	(version 20260206)
	(generator "pcbnew")
	(generator_version "10.0")
	(general
		(thickness 1.6)
		(legacy_teardrops no)
	)
	(paper "A4")
	(title_block
		(title "04192023_DAF0TMB3IC0_F0TG_MB_C_brd_V02_OCP.brd")
		(comment 1 "Grand Teton / footprints 4535-4536 of 8354")
	)
	(layers
		(0 "F.Cu" signal "TOP")
		(4 "In1.Cu" signal "GND")
		(6 "In2.Cu" signal "IN1")
		(8 "In3.Cu" signal "GND1")
		(10 "In4.Cu" signal "IN2")
		(12 "In5.Cu" signal "GND2")
		(14 "In6.Cu" signal "IN3")
		(16 "In7.Cu" signal "GND3")
		(18 "In8.Cu" signal "VCC")
		(20 "In9.Cu" signal "VCC1")
		(22 "In10.Cu" signal "GND4")
		(24 "In11.Cu" signal "IN4")
		(26 "In12.Cu" signal "GND5")
		(28 "In13.Cu" signal "IN5")
		(30 "In14.Cu" signal "GND6")
		(32 "In15.Cu" signal "IN6")
		(34 "In16.Cu" signal "GND7")
		(2 "B.Cu" signal "BOTTOM")
		(9 "F.Adhes" user "F.Adhesive")
		(11 "B.Adhes" user "B.Adhesive")
		(13 "F.Paste" user "Package Geometry/Pastemask Top")
		(15 "B.Paste" user "Package Geometry/Pastemask Bottom")
		(5 "F.SilkS" user "Ref Des/Silkscreen Top")
		(7 "B.SilkS" user "Ref Des/Silkscreen Bottom")
		(1 "F.Mask" user "Board Geometry/Soldermask Top")
		(3 "B.Mask" user "Board Geometry/Soldermask Bottom")
		(17 "Dwgs.User" user "User.Drawings")
		(19 "Cmts.User" user "User.Comments")
		(21 "Eco1.User" user "User.Eco1")
		(23 "Eco2.User" user "User.Eco2")
		(25 "Edge.Cuts" user "Board Geometry/Outline")
		(27 "Margin" user)
		(31 "F.CrtYd" user "Package Geometry/Place Bound Top")
		(29 "B.CrtYd" user "Package Geometry/Place Bound Bottom")
		(35 "F.Fab" user "Ref Des/Assembly Top")
		(33 "B.Fab" user "Ref Des/Assembly Bottom")
	)
	(footprint ""
		(layer "F.Cu")
		(at 64.591438 -31.887922 90)
		(property "Reference" "PC2167"
			(at 0 0 90)
			(layer "F.SilkS")
			(hide yes)
			(effects
				(font
					(size 1.27 1.27)
				)
			)
		)
		(property "Value" ""
			(at 0 0 90)
			(layer "F.Fab")
			(effects
				(font
					(size 1.27 1.27)
				)
			)
		)
		(duplicate_pad_numbers_are_jumpers no)
		(fp_line
			(start 0.7874 -0.4064)
			(end 0.7874 0.4064)
			(stroke
				(width 0.1524)
				(type default)
			)
			(layer "F.SilkS")
		)
		(fp_line
			(start -0.7874 -0.4064)
			(end 0.7874 -0.4064)
			(stroke
				(width 0.1524)
				(type default)
			)
			(layer "F.SilkS")
		)
		(fp_line
			(start 0.7874 0.4064)
			(end -0.7874 0.4064)
			(stroke
				(width 0.1524)
				(type default)
			)
			(layer "F.SilkS")
		)
		(fp_line
			(start -0.7874 0.4064)
			(end -0.7874 -0.4064)
			(stroke
				(width 0.1524)
				(type default)
			)
			(layer "F.SilkS")
		)
		(fp_line
			(start -0.12065 -0.305054)
			(end -0.12065 -0.2794)
			(stroke
				(width 0.1)
				(type default)
			)
			(layer "F.Fab")
		)
		(fp_line
			(start -0.67945 -0.305054)
			(end -0.12065 -0.305054)
			(stroke
				(width 0.1)
				(type default)
			)
			(layer "F.Fab")
		)
		(fp_line
			(start 0.67945 -0.3048)
			(end 0.67945 0.3048)
			(stroke
				(width 0.1)
				(type default)
			)
			(layer "F.Fab")
		)
		(fp_line
			(start 0.12065 -0.3048)
			(end 0.67945 -0.3048)
			(stroke
				(width 0.1)
				(type default)
			)
			(layer "F.Fab")
		)
		(fp_line
			(start 0.12065 -0.2794)
			(end 0.12065 -0.3048)
			(stroke
				(width 0.1)
				(type default)
			)
			(layer "F.Fab")
		)
		(fp_line
			(start -0.12065 -0.2794)
			(end 0.12065 -0.2794)
			(stroke
				(width 0.1)
				(type default)
			)
			(layer "F.Fab")
		)
		(fp_line
			(start 0.120396 0.2794)
			(end -0.12065 0.2794)
			(stroke
				(width 0.1)
				(type default)
			)
			(layer "F.Fab")
		)
		(fp_line
			(start -0.12065 0.2794)
			(end -0.12065 0.3048)
			(stroke
				(width 0.1)
				(type default)
			)
			(layer "F.Fab")
		)
		(fp_line
			(start 0.67945 0.3048)
			(end 0.120396 0.3048)
			(stroke
				(width 0.1)
				(type default)
			)
			(layer "F.Fab")
		)
		(fp_line
			(start 0.120396 0.3048)
			(end 0.120396 0.2794)
			(stroke
				(width 0.1)
				(type default)
			)
			(layer "F.Fab")
		)
		(fp_line
			(start -0.12065 0.3048)
			(end -0.67945 0.3048)
			(stroke
				(width 0.1)
				(type default)
			)
			(layer "F.Fab")
		)
		(fp_line
			(start -0.67945 0.3048)
			(end -0.67945 -0.305054)
			(stroke
				(width 0.1)
				(type default)
			)
			(layer "F.Fab")
		)
		(pad "1" smd circle
			(at -0.40005 0 90)
			(size 0 0)
			(layers "F.Cu" "F.Mask" "F.Paste")
			(net "P12V_OCP_IMON_2")
		)
		(pad "2" smd circle
			(at 0.40005 0 90)
			(size 0 0)
			(layers "F.Cu" "F.Mask" "F.Paste")
			(net "GND")
		)
	)
	(footprint ""
		(layer "F.Cu")
		(at 94.14891 -340.240874)
		(property "Reference" "PR270"
			(at 0 0 0)
			(layer "F.SilkS")
			(hide yes)
			(effects
				(font
					(size 1.27 1.27)
				)
			)
		)
		(property "Value" ""
			(at 0 0 0)
			(layer "F.Fab")
			(effects
				(font
					(size 1.27 1.27)
				)
			)
		)
		(duplicate_pad_numbers_are_jumpers no)
		(fp_line
			(start -0.7874 -0.4064)
			(end 0.7874 -0.4064)
			(stroke
				(width 0.1524)
				(type default)
			)
			(layer "F.SilkS")
		)
		(fp_line
			(start -0.7874 0.4064)
			(end -0.7874 -0.4064)
			(stroke
				(width 0.1524)
				(type default)
			)
			(layer "F.SilkS")
		)
		(fp_line
			(start 0.7874 -0.4064)
			(end 0.7874 0.4064)
			(stroke
				(width 0.1524)
				(type default)
			)
			(layer "F.SilkS")
		)
		(fp_line
			(start 0.7874 0.4064)
			(end -0.7874 0.4064)
			(stroke
				(width 0.1524)
				(type default)
			)
			(layer "F.SilkS")
		)
		(fp_line
			(start -0.67945 -0.305054)
			(end -0.12065 -0.305054)
			(stroke
				(width 0.1)
				(type default)
			)
			(layer "F.Fab")
		)
		(fp_line
			(start -0.67945 0.3048)
			(end -0.67945 -0.305054)
			(stroke
				(width 0.1)
				(type default)
			)
			(layer "F.Fab")
		)
		(fp_line
			(start -0.12065 -0.305054)
			(end -0.12065 -0.2794)
			(stroke
				(width 0.1)
				(type default)
			)
			(layer "F.Fab")
		)
		(fp_line
			(start -0.12065 -0.2794)
			(end 0.12065 -0.2794)
			(stroke
				(width 0.1)
				(type default)
			)
			(layer "F.Fab")
		)
		(fp_line
			(start -0.12065 0.2794)
			(end -0.12065 0.3048)
			(stroke
				(width 0.1)
				(type default)
			)
			(layer "F.Fab")
		)
		(fp_line
			(start -0.12065 0.3048)
			(end -0.67945 0.3048)
			(stroke
				(width 0.1)
				(type default)
			)
			(layer "F.Fab")
		)
		(fp_line
			(start 0.120396 0.2794)
			(end -0.12065 0.2794)
			(stroke
				(width 0.1)
				(type default)
			)
			(layer "F.Fab")
		)
		(fp_line
			(start 0.120396 0.3048)
			(end 0.120396 0.2794)
			(stroke
				(width 0.1)
				(type default)
			)
			(layer "F.Fab")
		)
		(fp_line
			(start 0.12065 -0.3048)
			(end 0.67945 -0.3048)
			(stroke
				(width 0.1)
				(type default)
			)
			(layer "F.Fab")
		)
		(fp_line
			(start 0.12065 -0.2794)
			(end 0.12065 -0.3048)
			(stroke
				(width 0.1)
				(type default)
			)
			(layer "F.Fab")
		)
		(fp_line
			(start 0.67945 -0.3048)
			(end 0.67945 0.3048)
			(stroke
				(width 0.1)
				(type default)
			)
			(layer "F.Fab")
		)
		(fp_line
			(start 0.67945 0.3048)
			(end 0.120396 0.3048)
			(stroke
				(width 0.1)
				(type default)
			)
			(layer "F.Fab")
		)
		(pad "1" smd circle
			(at -0.40005 0)
			(size 0 0)
			(layers "F.Cu" "F.Mask" "F.Paste")
			(net "PVDDCR_CPU1_P1_LSET5")
		)
		(pad "2" smd circle
			(at 0.40005 0)
			(size 0 0)
			(layers "F.Cu" "F.Mask" "F.Paste")
			(net "GND")
		)
	)
)
